G04 ================== begin FILE IDENTIFICATION RECORD ==================*
G04 Layout Name:  13948-1b.brd*
G04 Film Name:    P_OUTLINE*
G04 File Format:  Gerber RS274X*
G04 File Origin:  Cadence Allegro 16.5-S045*
G04 Origin Date:  Thu Nov 13 15:45:41 2014*
G04 *
G04 Layer:  BOARD GEOMETRY/PANEL_OUTLINE*
G04 *
G04 Offset:    (0.00 0.00)*
G04 Mirror:    No*
G04 Mode:      Positive*
G04 Rotation:  0*
G04 FullContactRelief:  No*
G04 UndefLineWidth:     6.00*
G04 ================== end FILE IDENTIFICATION RECORD ====================*
%FSLAX35Y35*MOIN*%
%IR0*IPPOS*OFA0.00000B0.00000*MIA0B0*SFA1.00000B1.00000*%
%ADD10C,.006*%
G75*
%LPD*%
G75*
G54D10*
G01X1Y-17717D02*
G03X7875Y-25591I7874J0D01*
G01X1Y299252D02*
Y-10394D01*
G01Y-17717D02*
G03X7875Y-25591I7874J0D01*
G01X1Y299252D02*
Y-10394D01*
G01Y-17717D02*
Y-10394D01*
G01D02*
Y-17723D01*
G01X0Y11811D02*
Y0D01*
G01X92520Y299252D02*
X1D01*
G01X92520D02*
X1D01*
G01X0Y318937D02*
G03X11811Y307126I11811J0D01*
G01X0Y968503D02*
Y318937D01*
G01X19685Y988189D02*
G03X0Y968503I0J-19685D01*
G01X43950Y996063D02*
X1D01*
G01X43950D02*
X1D01*
G01Y1008622D02*
Y996063D01*
G01Y1008622D02*
Y996063D01*
G01X15001Y1023622D02*
G03X1Y1008622I0J-15000D01*
G01X15001Y1023622D02*
G03X1Y1008622I0J-15000D01*
G01X7875Y-25591D02*
X45337D01*
G01X7875D02*
X45337D01*
G01X11811Y307126D02*
X100394D01*
G01X10710Y1008622D02*
G03X19292I4291J0D01*
G01D02*
G03X10710I-4291J0D01*
G01X99804Y1023622D02*
X15001D01*
G01X99804D02*
X15001D01*
G01X103740Y988189D02*
X19685D01*
G01X53211Y-25591D02*
G03X45337I-3937J0D01*
G01X53211D02*
G03X45337I-3937J0D01*
G01X53211D02*
G03X45337I-3937J0D01*
G01X53211D02*
G03X45337I-3937J0D01*
G01X43950Y988189D02*
G03Y996063I0J3937D01*
G01Y988189D02*
G03Y996063I0J3937D01*
G01X53211Y-25591D02*
X1392127D01*
G01X53211D02*
X1392127D01*
G01X69147Y996063D02*
G03Y988189I0J-3937D01*
G01Y996063D02*
G03Y988189I0J-3937D01*
G01X99804Y996063D02*
X69147D01*
G01X99804D02*
X69147D01*
G01X94412Y72220D02*
G03X85830Y72219I-4291J-1D01*
G01D02*
G03X94412Y72220I4291J0D01*
G01X100394Y291377D02*
G03X92520Y299252I-7874J1D01*
G01X100394Y291377D02*
G03X92520Y299252I-7874J1D01*
G01X99804Y1023622D02*
Y996063D01*
G01Y1023622D02*
Y996063D01*
G01X100394Y236259D02*
G03X116142Y220511I15748J0D01*
G01D02*
X232088D01*
G01X100394Y236259D02*
G03X116142Y220511I15748J0D01*
G01D02*
X232088D01*
G01X116142Y228385D02*
X239961D01*
G01X108268Y236259D02*
G03X116142Y228385I7874J0D01*
G01X108268Y299252D02*
Y236259D01*
G01X100395Y240899D02*
X100394Y236259D01*
G01X100395Y240899D02*
X100394Y236259D01*
G01X108269Y240899D02*
G03X100395I-3937J0D01*
G01X108269D02*
G03X100395I-3937J0D01*
G01Y266096D02*
G03X108269I3937J-1D01*
G01X100395D02*
G03X108269I3937J-1D01*
G01X100395D02*
X100394Y291377D01*
G01X100395Y266096D02*
X100394Y291377D01*
G01X108268Y299252D02*
G03X100394Y307126I-7874J0D01*
G01X103740Y988189D02*
G03X107677Y992126I0J3937D01*
G01Y1018109D02*
Y992126D01*
G01X136024Y1018109D02*
X136023Y1021653D01*
X134055Y1023622D01*
X109645D01*
X107677Y1021653D01*
Y1018109D01*
G01X136024Y994290D02*
G03X143505I3740J0D01*
G01X136024D02*
Y1018109D01*
G01X143504D02*
Y994290D01*
G01X187598Y1018109D02*
Y1021653D01*
X185630Y1023622D01*
X145472D01*
X143504Y1021653D01*
Y1018109D01*
G01X151575Y220511D02*
X226378D01*
G01X151575D02*
X226378D01*
G01X187598Y992126D02*
Y1018109D01*
G01Y992126D02*
G03X191535Y988189I3937J0D01*
G01X261220D02*
X191535D01*
G01X212681Y996063D02*
X195473D01*
G01D02*
Y1023622D01*
G01X212681Y996063D02*
X195473D01*
G01D02*
Y1023622D01*
G01D02*
X257284D01*
G01X195473D02*
X257284D01*
G01X212681Y988189D02*
G03Y996063I0J3937D01*
G01Y988189D02*
G03Y996063I0J3937D01*
G01X222751Y1008622D02*
G03X231333I4291J0D01*
G01D02*
G03X222751I-4291J0D01*
G01X243898Y70866D02*
G03X247835Y66928I3937J-1D01*
G01X243898Y224448D02*
Y70866D01*
G01X236025Y164487D02*
Y70866D01*
G01D02*
G03X247836Y59055I11811J0D01*
G01X236025Y164487D02*
Y70866D01*
G01D02*
G03X247836Y59055I11811J0D01*
G01X243899Y164487D02*
G03X236025I-3937J0D01*
G01X243899D02*
G03X236025I-3937J0D01*
G01Y189684D02*
G03X243899I3937J0D01*
G01X236025D02*
G03X243899I3937J0D01*
G01X236025D02*
Y216574D01*
G01Y189684D02*
Y216574D01*
G01D02*
G03X232088Y220511I-3937J0D01*
G01X236025Y216574D02*
G03X232088Y220511I-3937J0D01*
G01X243898Y224448D02*
G03X239961Y228385I-3937J0D01*
G01X237877Y996063D02*
G03Y988189I0J-3937D01*
G01Y996063D02*
G03Y988189I0J-3937D01*
G01X257284Y996063D02*
X237877D01*
G01X257284D02*
X237877D01*
G01X247835Y66929D02*
X289174D01*
G01X247836Y59055D02*
X285237D01*
G01X247836D02*
X285237D01*
G01X261220Y988189D02*
G03X265157Y992126I0J3937D01*
G01X257284Y1023622D02*
Y996063D01*
G01Y1023622D02*
Y996063D01*
G01X265157Y1018109D02*
Y992126D01*
G01X545472Y1018109D02*
Y1021653D01*
X543504Y1023622D01*
X267126D01*
X265157Y1021653D01*
Y1018109D01*
G01X293111Y3937D02*
G03X297047Y0I3937J0D01*
G01X293110Y62992D02*
Y3937D01*
G01X285237D02*
G03X297048Y-7874I11811J0D01*
G01X285237Y59055D02*
Y3937D01*
G01D02*
G03X297048Y-7874I11811J0D01*
G01X285237Y59055D02*
Y3937D01*
G01X293111Y62992D02*
G03X289174Y66929I-3937J0D01*
G01X297047Y0D02*
X1108209D01*
G01X297037Y-7874D02*
X301187D01*
G01D02*
G03Y0I0J3937D01*
G01X297037Y-7874D02*
X301187D01*
G01D02*
G03Y0I0J3937D01*
G01X318510Y-7874D02*
X515333D01*
G01X318510Y0D02*
G03Y-7874I0J-3937D01*
G01D02*
X515333D01*
G01X318510Y0D02*
G03Y-7874I0J-3937D01*
G01X515302D02*
G03Y0I0J3937D01*
G01Y-7874D02*
G03Y0I0J3937D01*
G01X540499Y-7874D02*
X727049D01*
G01X540499Y0D02*
G03Y-7874I0J-3937D01*
G01D02*
X727049D01*
G01X540499Y0D02*
G03Y-7874I0J-3937D01*
G01X545472Y994290D02*
G03X552953I3740J1D01*
G01X545472D02*
Y1018109D01*
G01X552953D02*
Y994290D01*
G01X597047Y1018109D02*
Y1021653D01*
X595078Y1023622D01*
X554921D01*
X552952Y1021653D01*
X552953Y1018109D01*
G01X597047Y992126D02*
Y1018109D01*
G01X597048Y992126D02*
G03X600984Y988189I3937J0D01*
G01X713189D02*
X600984D01*
G01X641198Y996063D02*
X604922D01*
G01D02*
Y1023622D01*
G01X641198Y996063D02*
X604922D01*
G01D02*
Y1023622D01*
G01D02*
X709253D01*
G01X604922D02*
X709253D01*
G01X641198Y988189D02*
G03Y996063I0J3937D01*
G01Y988189D02*
G03Y996063I0J3937D01*
G01X649684Y1008622D02*
G03X658266I4291J0D01*
G01D02*
G03X649684I-4291J0D01*
G01X666395Y996063D02*
G03Y988189I0J-3937D01*
G01Y996063D02*
G03Y988189I0J-3937D01*
G01X709253Y996063D02*
X666395D01*
G01X709253D02*
X666395D01*
G01X713189Y988189D02*
G03X717126Y992126I0J3937D01*
G01Y1018109D02*
Y992126D01*
G01X709253Y1023622D02*
Y996063D01*
G01Y1023622D02*
Y996063D01*
G01X745472Y1018109D02*
Y1021653D01*
X743504Y1023622D01*
X719094D01*
X717126Y1021653D01*
Y1018109D01*
G01X727049Y-7874D02*
G03Y0I0J3937D01*
G01Y-7874D02*
G03Y0I0J3937D01*
G01X752246Y-7874D02*
X984201D01*
G01X752246Y0D02*
G03Y-7874I0J-3937D01*
G01D02*
X984201D01*
G01X752246Y0D02*
G03Y-7874I0J-3937D01*
G01X745472Y994290D02*
G03X752953I3741J1D01*
G01X745472D02*
Y1018109D01*
G01X752953D02*
Y994290D01*
G01X797047Y1018109D02*
Y1021653D01*
X795078Y1023622D01*
X754921D01*
X752952Y1021653D01*
X752953Y1018109D01*
G01X797047Y992126D02*
Y1018109D01*
G01X797048Y992126D02*
G03X800984Y988189I3937J0D01*
G01X902165D02*
X800984D01*
G01X859109Y996063D02*
X804922D01*
G01D02*
Y1023622D01*
G01X859109Y996063D02*
X804922D01*
G01D02*
Y1023622D01*
G01D02*
X1325399D01*
G01X804922D02*
X1325399D01*
G01X859109Y988189D02*
G03Y996063I0J3937D01*
G01Y988189D02*
G03Y996063I0J3937D01*
G01X884306D02*
G03Y988189I0J-3937D01*
G01Y996063D02*
G03Y988189I0J-3937D01*
G01X902166Y996063D02*
X884306D01*
G01X902166D02*
X884306D01*
G01X921850Y968503D02*
G03X902165Y988189I-19685J1D01*
G01X929725Y968504D02*
G03X902166Y996063I-27559J0D01*
G01D02*
X902195D01*
G01X929725Y968504D02*
G03X902166Y996063I-27559J0D01*
G01D02*
X902195D01*
G01X921850Y775590D02*
Y968503D01*
G01Y775590D02*
G03X925787Y771653I3937J0D01*
G01X984843D02*
X925787D01*
G01X929725Y779527D02*
Y886881D01*
G01Y779527D02*
X980906D01*
G01X929725D02*
Y886881D01*
G01Y779527D02*
X980906D01*
G01X929725Y886881D02*
G03X921851I-3937J1D01*
G01X929725D02*
G03X921851I-3937J1D01*
G01Y912079D02*
G03X929725I3937J-1D01*
G01X921851D02*
G03X929725I3937J-1D01*
G01Y912078D02*
Y968504D01*
G01Y912078D02*
Y968504D01*
G01X959606Y850829D02*
G03X951024I-4291J0D01*
G01D02*
G03X959606I4291J0D01*
G01X984201Y-7874D02*
G03Y0I0J3937D01*
G01Y-7874D02*
G03Y0I0J3937D01*
G01X984843Y771653D02*
G03X988780Y775590I0J3937D01*
G01X980907Y886881D02*
X980906Y779527D01*
G01X980907Y886881D02*
X980906Y779527D01*
G01X988781Y886881D02*
G03X980907I-3937J1D01*
G01X988781D02*
G03X980907I-3937J1D01*
G01Y912079D02*
G03X988781I3937J-1D01*
G01X980907D02*
G03X988781I3937J-1D01*
G01X980907D02*
X980906Y968504D01*
G01X980907Y912079D02*
X980906Y968504D01*
G01X1008465Y996063D02*
G03X980906Y968504I0J-27559D01*
G01X1008465Y996063D02*
G03X980906Y968504I0J-27559D01*
G01X988780Y968503D02*
Y775590D01*
G01X1008465Y988189D02*
G03X988780Y968503I0J-19685D01*
G01X1009398Y-7874D02*
X1108229D01*
G01X1009398Y0D02*
G03Y-7874I-1J-3937D01*
G01D02*
X1108229D01*
G01X1009398Y0D02*
G03Y-7874I-1J-3937D01*
G01X1380315Y988189D02*
X1008465D01*
G01X1070592Y996063D02*
X1008466D01*
G01X1070592D02*
X1008466D01*
G01X1070592Y988189D02*
G03Y996063I0J3937D01*
G01Y988189D02*
G03Y996063I0J3937D01*
G01X1095789D02*
G03Y988189I0J-3937D01*
G01Y996063D02*
G03Y988189I0J-3937D01*
G01X1325399Y996063D02*
X1095789D01*
G01X1325399D02*
X1095789D01*
G01X1112146Y3937D02*
Y210629D01*
G01X1108209Y0D02*
G03X1112146Y3937I0J3937D01*
G01X1108208Y-7874D02*
G03X1120020Y3938I1J11811D01*
G01X1108208Y-7874D02*
G03X1120020Y3938I1J11811D01*
G01Y99950D02*
G03X1112146I-3937J0D01*
G01X1120020D02*
G03X1112146I-3937J0D01*
G01Y125147D02*
G03X1120020I3937J0D01*
G01X1112146D02*
G03X1120020I3937J0D01*
G01X1116083Y214566D02*
X1194824D01*
G01X1116083D02*
G03X1112146Y210629I0J-3937D01*
G01X1120020Y99950D02*
Y3938D01*
G01Y99950D02*
Y3938D01*
G01Y125147D02*
Y206693D01*
G01Y125147D02*
Y206693D01*
G01X1120021D02*
X1190887D01*
G01X1120021D02*
X1190887D01*
G01X1161386Y128841D02*
G03X1152804I-4291J0D01*
G01D02*
G03X1161386I4291J0D01*
G01X1198760Y3937D02*
G03X1210571Y-7874I11811J0D01*
G01X1198760Y3937D02*
G03X1210571Y-7874I11811J0D01*
G01X1198761Y97100D02*
X1198760Y3937D01*
G01X1198761Y97100D02*
X1198760Y3937D01*
G01X1206635Y97100D02*
G03X1198761I-3937J0D01*
G01X1206635D02*
G03X1198761I-3937J0D01*
G01Y122297D02*
G03X1206635I3937J0D01*
G01X1198761D02*
G03X1206635I3937J0D01*
G01X1198761D02*
Y168002D01*
G01Y122297D02*
Y168002D01*
G01X1190887Y179134D02*
G03X1198761Y167998I11811J0D01*
G01X1190887Y179134D02*
G03X1198761Y167998I11811J0D01*
G01X1198760Y179133D02*
G03X1202697Y175196I3937J0D01*
G01X1198760Y210629D02*
Y179133D01*
G01X1190887Y206693D02*
Y179134D01*
G01Y206693D02*
Y179134D01*
G01X1198760Y210629D02*
G03X1194824Y214566I-3937J0D01*
G01X1210571Y0D02*
X1396063D01*
G01X1206634Y3937D02*
G03X1210571Y0I3937J0D01*
G01X1206634Y171259D02*
Y3937D01*
G01X1210552Y-7874D02*
X1210572D01*
G01D02*
G03Y0I0J3937D01*
G01X1210552Y-7874D02*
X1210572D01*
G01D02*
G03Y0I0J3937D01*
G01X1206634Y171259D02*
G03X1202697Y175196I-3937J0D01*
G01X1226320Y-7874D02*
X1380317D01*
G01X1226320Y0D02*
G03Y-7874I0J-3937D01*
G01D02*
X1380317D01*
G01X1226320Y0D02*
G03Y-7874I0J-3937D01*
G01X1354801Y996063D02*
X1325399D01*
G01X1354801D02*
X1325399D01*
G01Y1023622D02*
X1385001D01*
G01X1325399D02*
X1385001D01*
G01X1354801Y988189D02*
G03Y996063I0J3937D01*
G01Y988189D02*
G03Y996063I0J3937D01*
G01X1380316Y-7874D02*
G03Y0I0J3937D01*
G01Y-7874D02*
G03Y0I0J3937D01*
G01X1400000Y968503D02*
G03X1380315Y988189I-19685J1D01*
G01X1379998Y996063D02*
G03Y988189I0J-3937D01*
G01Y996063D02*
G03Y988189I0J-3937D01*
G01X1400001Y996063D02*
X1379998D01*
G01X1400001D02*
X1379998D01*
G01X1392127Y-25591D02*
G03X1400001Y-17717I0J7874D01*
G01X1392167Y-15015D02*
G03X1383585I-4291J0D01*
G01D02*
G03X1392167I4291J0D01*
G01X1392127Y-25591D02*
G03X1400001Y-17717I0J7874D01*
G01X1396063Y0D02*
G03X1400000Y3937I0J3937D01*
G01X1396064Y-7874D02*
X1400001D01*
G01X1396064Y0D02*
G03Y-7874I0J-3937D01*
G01D02*
X1400001D01*
G01X1396064Y0D02*
G03Y-7874I0J-3937D01*
G01X1380710Y1008622D02*
G03X1389292I4291J0D01*
G01D02*
G03X1380710I-4291J0D01*
G01X1400001D02*
G03X1385001Y1023622I-15000J0D01*
G01X1400001Y1008622D02*
G03X1385001Y1023622I-15000J0D01*
G01X1400001Y-17717D02*
Y-7874D01*
G01Y-17717D02*
Y-7874D01*
G01X1400000Y3937D02*
Y968503D01*
G01X1400001Y996063D02*
Y1008622D01*
G01Y996063D02*
Y1008622D01*
M02*
